#ISCELL
  pure_quanta quanta_title_block_c *
  *
#ISCELL
  mstr_standard offpage *
  page132_i10
#ISCELL
  mstr_standard offpage *
  page132_i11
#CELL
  pure_quanta q_res *
  page132_i12
#CELL
  pure_quanta q_res *
  page132_i15
#CELL
  pure_quanta q_res *
  page132_i17
#ISCELL
  mstr_standard offpage *
  page132_i18
#ISCELL
  mstr_standard offpage *
  page132_i21
#ISCELL
  mstr_standard offpage *
  page132_i23
#CELL
  pure_quanta q_res *
  page132_i33
#ISCELL
  mstr_standard offpage *
  page132_i34
#ISCELL
  pure_quanta_power universal_gnd *
  page132_i35
#CELL
  pure_quanta mosfet_dual_6p *
  page132_i38
#ISCELL
  standard offpage *
  page132_i39
#ISCELL
  standard offpage *
  page132_i40
#ISCELL
  pure_quanta_power universal_gnd *
  page132_i42
#ISCELL
  pure_quanta_power universal_power *
  page132_i43
#CELL
  pure_quanta q_res *
  page132_i44
#ISCELL
  pure_quanta_power universal_power *
  page132_i45
#CELL
  pure_quanta q_res *
  page132_i46
#CELL
  pure_quanta q_res *
  page132_i48
#ISCELL
  pure_quanta_power universal_power *
  page132_i49
#CELL
  pure_quanta q_res *
  page132_i50
#ISCELL
  standard offpage *
  page132_i51
#CELL
  pure_quanta q_res *
  page132_i8
#CELL
  pure_quanta q_res *
  page132_i9
